(kicad_pcb
	(version 20260206)
	(generator "pcbnew")
	(generator_version "10.0")
	(general
		(thickness 1.6)
		(legacy_teardrops no)
	)
	(paper "A4")
	(title_block
		(title "v1-tray-backplane — T6M_tray_BP_c_1023_1120.brd")
		(comment 1 "Open CloudServer (Microsoft) / footprints 27-30 of 170")
	)
	(layers
		(0 "F.Cu" signal "TOP")
		(4 "In1.Cu" signal "GND")
		(6 "In2.Cu" signal "IN1")
		(8 "In3.Cu" signal "VCC")
		(10 "In4.Cu" signal "VCC1")
		(12 "In5.Cu" signal "IN2")
		(14 "In6.Cu" signal "GND1")
		(2 "B.Cu" signal "BOTTOM")
		(9 "F.Adhes" user "F.Adhesive")
		(11 "B.Adhes" user "B.Adhesive")
		(13 "F.Paste" user "Package Geometry/Pastemask Top")
		(15 "B.Paste" user "Package Geometry/Pastemask Bottom")
		(5 "F.SilkS" user "Ref Des/Silkscreen Top")
		(7 "B.SilkS" user "Ref Des/Silkscreen Bottom")
		(1 "F.Mask" user "Board Geometry/Soldermask Top")
		(3 "B.Mask" user "Board Geometry/Soldermask Bottom")
		(17 "Dwgs.User" user "User.Drawings")
		(19 "Cmts.User" user "User.Comments")
		(21 "Eco1.User" user "User.Eco1")
		(23 "Eco2.User" user "User.Eco2")
		(25 "Edge.Cuts" user "Board Geometry/Outline")
		(27 "Margin" user)
		(31 "F.CrtYd" user "Package Geometry/Place Bound Top")
		(29 "B.CrtYd" user "Package Geometry/Place Bound Bottom")
		(35 "F.Fab" user "Ref Des/Assembly Top")
		(33 "B.Fab" user "Ref Des/Assembly Bottom")
	)
	(footprint ""
		(layer "F.Cu")
		(at 310.308752 -30.368494 180)
		(property "Reference" "R54"
			(at 6.826504 0.72136 0)
			(unlocked yes)
			(layer "F.SilkS")
			(effects
				(font
					(size 0.7874 0.5842)
					(thickness 0.1524)
				)
				(justify left)
			)
		)
		(property "Value" ""
			(at 0 0 180)
			(layer "F.Fab")
			(effects
				(font
					(size 1.27 1.27)
				)
			)
		)
		(duplicate_pad_numbers_are_jumpers no)
		(fp_line
			(start 0.7874 0.4064)
			(end -0.7874 0.4064)
			(stroke
				(width 0.1524)
				(type default)
			)
			(layer "F.SilkS")
		)
		(fp_line
			(start 0.7874 -0.4064)
			(end 0.7874 0.4064)
			(stroke
				(width 0.1524)
				(type default)
			)
			(layer "F.SilkS")
		)
		(fp_line
			(start -0.7874 0.4064)
			(end -0.7874 -0.4064)
			(stroke
				(width 0.1524)
				(type default)
			)
			(layer "F.SilkS")
		)
		(fp_line
			(start -0.7874 -0.4064)
			(end 0.7874 -0.4064)
			(stroke
				(width 0.1524)
				(type default)
			)
			(layer "F.SilkS")
		)
		(fp_poly
			(pts
				(xy -0.508 0.2794) (xy -0.508 0.2286) (xy -0.635 0.2286) (xy -0.635 -0.254) (xy -0.5334 -0.254)
				(xy -0.5334 -0.2794) (xy 0.5334 -0.2794) (xy 0.5334 -0.254) (xy 0.635 -0.254) (xy 0.635 0.254) (xy 0.5334 0.254)
				(xy 0.5334 0.2794)
			)
			(stroke
				(width 0)
				(type default)
			)
			(fill no)
			(layer "F.CrtYd")
		)
		(pad "1" smd rect
			(at 0.40005 0 180)
			(size 0.4572 0.508)
			(layers "F.Cu" "F.Mask" "F.Paste")
			(net "GND")
		)
		(pad "2" smd rect
			(at -0.40005 0 180)
			(size 0.4572 0.508)
			(layers "F.Cu" "F.Mask" "F.Paste")
			(net "ENET10G_4_TX_FAULT")
		)
	)
	(footprint ""
		(layer "F.Cu")
		(at 89.41816 -26.152094 180)
		(property "Reference" "R45"
			(at 7.13232 -0.21844 0)
			(unlocked yes)
			(layer "F.SilkS")
			(effects
				(font
					(size 0.7874 0.5842)
					(thickness 0.1524)
				)
				(justify left)
			)
		)
		(property "Value" ""
			(at 0 0 180)
			(layer "F.Fab")
			(effects
				(font
					(size 1.27 1.27)
				)
			)
		)
		(duplicate_pad_numbers_are_jumpers no)
		(fp_line
			(start 0.7874 0.4064)
			(end -0.7874 0.4064)
			(stroke
				(width 0.1524)
				(type default)
			)
			(layer "F.SilkS")
		)
		(fp_line
			(start 0.7874 -0.4064)
			(end 0.7874 0.4064)
			(stroke
				(width 0.1524)
				(type default)
			)
			(layer "F.SilkS")
		)
		(fp_line
			(start -0.7874 0.4064)
			(end -0.7874 -0.4064)
			(stroke
				(width 0.1524)
				(type default)
			)
			(layer "F.SilkS")
		)
		(fp_line
			(start -0.7874 -0.4064)
			(end 0.7874 -0.4064)
			(stroke
				(width 0.1524)
				(type default)
			)
			(layer "F.SilkS")
		)
		(fp_poly
			(pts
				(xy -0.508 0.2794) (xy -0.508 0.2286) (xy -0.635 0.2286) (xy -0.635 -0.254) (xy -0.5334 -0.254)
				(xy -0.5334 -0.2794) (xy 0.5334 -0.2794) (xy 0.5334 -0.254) (xy 0.635 -0.254) (xy 0.635 0.254) (xy 0.5334 0.254)
				(xy 0.5334 0.2794)
			)
			(stroke
				(width 0)
				(type default)
			)
			(fill no)
			(layer "F.CrtYd")
		)
		(pad "1" smd rect
			(at 0.40005 0 180)
			(size 0.4572 0.508)
			(layers "F.Cu" "F.Mask" "F.Paste")
			(net "GND")
		)
		(pad "2" smd rect
			(at -0.40005 0 180)
			(size 0.4572 0.508)
			(layers "F.Cu" "F.Mask" "F.Paste")
			(net "ENET10G_2_RS1")
		)
	)
	(footprint ""
		(layer "F.Cu")
		(at 377.063 -29.859732 180)
		(property "Reference" "R80"
			(at -34.163 -18.064734 0)
			(unlocked yes)
			(layer "F.SilkS")
			(effects
				(font
					(size 0.7874 0.5842)
					(thickness 0.1524)
				)
				(justify left)
			)
		)
		(property "Value" ""
			(at 0 0 180)
			(layer "F.Fab")
			(effects
				(font
					(size 1.27 1.27)
				)
			)
		)
		(duplicate_pad_numbers_are_jumpers no)
		(fp_line
			(start 1.905 0.8636)
			(end -1.905 0.8636)
			(stroke
				(width 0.1524)
				(type default)
			)
			(layer "F.SilkS")
		)
		(fp_line
			(start 1.905 -0.8636)
			(end 1.905 0.8636)
			(stroke
				(width 0.1524)
				(type default)
			)
			(layer "F.SilkS")
		)
		(fp_line
			(start -1.905 0.8636)
			(end -1.905 -0.8636)
			(stroke
				(width 0.1524)
				(type default)
			)
			(layer "F.SilkS")
		)
		(fp_line
			(start -1.905 -0.8636)
			(end 1.905 -0.8636)
			(stroke
				(width 0.1524)
				(type default)
			)
			(layer "F.SilkS")
		)
		(fp_poly
			(pts
				(xy 1.524 0.6858) (xy 1.524 -0.6858) (xy 1.524 -0.7366) (xy -1.524 -0.7366) (xy -1.524 -0.6858)
				(xy -1.524 0.6858) (xy -1.524 0.7366) (xy 1.524 0.7366)
			)
			(stroke
				(width 0)
				(type default)
			)
			(fill no)
			(layer "F.CrtYd")
		)
		(pad "1" smd rect
			(at 0.94996 0 180)
			(size 1.1176 1.3716)
			(layers "F.Cu" "F.Mask" "F.Paste")
			(net "P3V3_BLAD2")
		)
		(pad "2" smd rect
			(at -0.94996 0 180)
			(size 1.1176 1.3716)
			(layers "F.Cu" "F.Mask" "F.Paste")
			(net "P3V3_10G_3_VCCT")
		)
	)
	(footprint ""
		(layer "F.Cu")
		(at 130.101848 -26.533094 180)
		(property "Reference" "R5"
			(at 61.651896 -5.14604 0)
			(unlocked yes)
			(layer "F.SilkS")
			(effects
				(font
					(size 0.7874 0.5842)
					(thickness 0.1524)
				)
				(justify left)
			)
		)
		(property "Value" ""
			(at 0 0 180)
			(layer "F.Fab")
			(effects
				(font
					(size 1.27 1.27)
				)
			)
		)
		(duplicate_pad_numbers_are_jumpers no)
		(fp_line
			(start 0.7874 0.4064)
			(end -0.7874 0.4064)
			(stroke
				(width 0.1524)
				(type default)
			)
			(layer "F.SilkS")
		)
		(fp_line
			(start 0.7874 -0.4064)
			(end 0.7874 0.4064)
			(stroke
				(width 0.1524)
				(type default)
			)
			(layer "F.SilkS")
		)
		(fp_line
			(start -0.7874 0.4064)
			(end -0.7874 -0.4064)
			(stroke
				(width 0.1524)
				(type default)
			)
			(layer "F.SilkS")
		)
		(fp_line
			(start -0.7874 -0.4064)
			(end 0.7874 -0.4064)
			(stroke
				(width 0.1524)
				(type default)
			)
			(layer "F.SilkS")
		)
		(fp_poly
			(pts
				(xy -0.508 0.2794) (xy -0.508 0.2286) (xy -0.635 0.2286) (xy -0.635 -0.254) (xy -0.5334 -0.254)
				(xy -0.5334 -0.2794) (xy 0.5334 -0.2794) (xy 0.5334 -0.254) (xy 0.635 -0.254) (xy 0.635 0.254) (xy 0.5334 0.254)
				(xy 0.5334 0.2794)
			)
			(stroke
				(width 0)
				(type default)
			)
			(fill no)
			(layer "F.CrtYd")
		)
		(pad "1" smd rect
			(at 0.40005 0 180)
			(size 0.4572 0.508)
			(layers "F.Cu" "F.Mask" "F.Paste")
			(net "P3V3_BLAD1")
		)
		(pad "2" smd rect
			(at -0.40005 0 180)
			(size 0.4572 0.508)
			(layers "F.Cu" "F.Mask" "F.Paste")
			(net "ENET10G_1_SDA")
		)
	)
)
